;LEADER: 12 
;HEADER: 
;CODE  : ASCII 
;FILE  : 9324_DA0F0TMBIJ0_F0T_Motherboard_J_v01_20230324_0910-bd-18-9.drl for backdrilling ... from layer BOTTOM to layer VCC
;DESIGN: 9324_DA0F0TMBIJ0_F0T_Motherboard_J_v01_20230324_0910.brd
;MUST-NOT-CUT-LAYER = GND3,  MAX_DRILL_DEPTH = 55.00 MILS,  MFG_STUB_LENGTH = 0.00 MILS
;   BackdrillSize 1. = 21.870000 Tolerance = +0.000000/-0.000000 NON_PLATED MILS Quantity = 256
%
G90
X0230906Y1710590
X0246654Y1710590
X0262402Y1710590
X0230906Y1705866
X0246654Y1705866
X0262402Y1705866
X0238780Y1714527
X0254528Y1714527
X0270276Y1714527
X0238780Y1709803
X0254528Y1709803
X0270276Y1709803
X0238780Y1686180
X0254528Y1686180
X0270276Y1686180
X0230906Y1682244
X0246654Y1682244
X0262402Y1682244
X0230906Y1677519
X0246654Y1677519
X0262402Y1677519
X0238780Y1681456
X0254528Y1681456
X0270276Y1681456
X0352953Y1681456
X0345079Y1682244
X0337205Y1681456
X0329331Y1682244
X0321457Y1681456
X0313583Y1682244
X0305709Y1681456
X0297835Y1682244
X0345079Y1677519
X0329331Y1677519
X0313583Y1677519
X0297835Y1677519
X0278150Y1682244
X0278150Y1677519
X0286024Y1681456
X0352953Y1714527
X0337205Y1714527
X0321457Y1714527
X0305709Y1714527
X0352953Y1709803
X0345079Y1710590
X0337205Y1709803
X0329331Y1710590
X0321457Y1709803
X0313583Y1710590
X0305709Y1709803
X0297835Y1710590
X0345079Y1705866
X0329331Y1705866
X0313583Y1705866
X0297835Y1705866
X0352953Y1686180
X0337205Y1686180
X0321457Y1686180
X0305709Y1686180
X0278150Y1710590
X0278150Y1705866
X0286024Y1714527
X0286024Y1709803
X0286024Y1686180
X0550197Y1728700
X0534449Y1728700
X0518701Y1728700
X0502953Y1728700
X0550197Y1723976
X0542323Y1724763
X0534449Y1723976
X0526575Y1724763
X0518701Y1723976
X0510827Y1724763
X0502953Y1723976
X0495079Y1724763
X0542323Y1720039
X0526575Y1720039
X0510827Y1720039
X0495079Y1720039
X0550197Y1700354
X0534449Y1700354
X0518701Y1700354
X0502953Y1700354
X0550197Y1695629
X0542323Y1696417
X0534449Y1695629
X0526575Y1696417
X0518701Y1695629
X0510827Y1696417
X0502953Y1695629
X0495079Y1696417
X0542323Y1691692
X0526575Y1691692
X0510827Y1691692
X0495079Y1691692
X0569882Y1728700
X0569882Y1723976
X0562008Y1724763
X0562008Y1720039
X0569882Y1700354
X0569882Y1695629
X0562008Y1696417
X0562008Y1691692
X0617126Y1728700
X0601378Y1728700
X0585630Y1728700
X0617126Y1723976
X0609252Y1724763
X0601378Y1723976
X0593504Y1724763
X0585630Y1723976
X0577756Y1724763
X0609252Y1720039
X0593504Y1720039
X0577756Y1720039
X0617126Y1700354
X0601378Y1700354
X0585630Y1700354
X0617126Y1695629
X0609252Y1696417
X0601378Y1695629
X0593504Y1696417
X0585630Y1695629
X0577756Y1696417
X0609252Y1691692
X0593504Y1691692
X0577756Y1691692
X1262402Y1714527
X1246654Y1714527
X1270276Y1710590
X1262402Y1709803
X1254528Y1710590
X1246654Y1709803
X1238780Y1710590
X1270276Y1705866
X1254528Y1705866
X1238780Y1705866
X1262402Y1686180
X1246654Y1686180
X1270276Y1682244
X1262402Y1681456
X1254528Y1682244
X1246654Y1681456
X1238780Y1682244
X1270276Y1677519
X1254528Y1677519
X1238780Y1677519
X1360827Y1681456
X1352953Y1682244
X1345079Y1681456
X1337205Y1682244
X1329331Y1681456
X1321457Y1682244
X1313583Y1681456
X1305709Y1682244
X1352953Y1677519
X1337205Y1677519
X1321457Y1677519
X1305709Y1677519
X1293898Y1681456
X1286024Y1682244
X1278150Y1681456
X1286024Y1677519
X1360827Y1714527
X1345079Y1714527
X1329331Y1714527
X1313583Y1714527
X1360827Y1709803
X1352953Y1710590
X1345079Y1709803
X1337205Y1710590
X1329331Y1709803
X1321457Y1710590
X1313583Y1709803
X1305709Y1710590
X1352953Y1705866
X1337205Y1705866
X1321457Y1705866
X1305709Y1705866
X1360827Y1686180
X1345079Y1686180
X1329331Y1686180
X1313583Y1686180
X1293898Y1714527
X1278150Y1714527
X1293898Y1709803
X1286024Y1710590
X1278150Y1709803
X1286024Y1705866
X1293898Y1686180
X1278150Y1686180
X1558071Y1728700
X1542323Y1728700
X1526575Y1728700
X1510827Y1728700
X1558071Y1723976
X1550197Y1724763
X1542323Y1723976
X1534449Y1724763
X1526575Y1723976
X1518701Y1724763
X1510827Y1723976
X1502953Y1724763
X1550197Y1720039
X1534449Y1720039
X1518701Y1720039
X1502953Y1720039
X1558071Y1700354
X1542323Y1700354
X1526575Y1700354
X1510827Y1700354
X1558071Y1695629
X1550197Y1696417
X1542323Y1695629
X1534449Y1696417
X1526575Y1695629
X1518701Y1696417
X1510827Y1695629
X1502953Y1696417
X1550197Y1691692
X1534449Y1691692
X1518701Y1691692
X1502953Y1691692
X1569882Y1724763
X1569882Y1720039
X1569882Y1696417
X1569882Y1691692
X1625000Y1728700
X1609252Y1728700
X1593504Y1728700
X1577756Y1728700
X1625000Y1723976
X1617126Y1724763
X1609252Y1723976
X1601378Y1724763
X1593504Y1723976
X1585630Y1724763
X1577756Y1723976
X1617126Y1720039
X1601378Y1720039
X1585630Y1720039
X1625000Y1700354
X1609252Y1700354
X1593504Y1700354
X1577756Y1700354
X1625000Y1695629
X1617126Y1696417
X1609252Y1695629
X1601378Y1696417
X1593504Y1695629
X1585630Y1696417
X1577756Y1695629
X1617126Y1691692
X1601378Y1691692
X1585630Y1691692
M30
